FILE_TYPE = MULTI_PHYS_TABLE;

PART 'BAT547F'

{========================================================================================}
:VALUE       | PART_TYPE | MATERIAL | PART_NUMBER       = STANDARD | LIFECYCLE      | PART_NUMBER       | JEDEC_TYPE    | DESCRIPTION                               | MANUFTR | MANUF_PN    | RD_CMPLS_LVL | CMPLS_LVL | CLASS | DIP_SMD | FP_ECN           | FROM_PJ     | DATA                           | EE_CHECK_LIST | STATUS | PSL | PREFERENCE | CREATOR | CREATEDAY  ;
{========================================================================================}
 'BAT547F'   | 'SMLF'    | 'IC'     | 'BC0BAT54Z53'(!)  = ''       | ''             | 'BC0BAT54Z53'     |'SOT23_123XB'| 'DIODE BAT54-7-F(30V.200MA SCHOTTKY)'     | 'DDS'   | 'BAT54-7-F' | ''           | 'EU'      | 'IC'  | ''      | ''               | 'S50-STEVE' | 'DDS_BAT54-7-F(A.C.S-7-F).pdf' | ''            | ''     | ''  | ''         | ''      | '20130912'
 'BAT547F'   | 'SMLF'    | 'EMPTY'  | 'BC0BAT54Z53'(!)  = ''       | ''             | 'BC0BAT54Z53'     |'SOT23_123XB'| 'DIODE BAT54-7-F(30V.200MA SCHOTTKY)'     | 'DDS'   | 'BAT54-7-F' | ''           | 'EU'      | 'IC'  | ''      | ''               | 'S50-STEVE' | 'DDS_BAT54-7-F(A.C.S-7-F).pdf' | ''            | ''     | ''  | ''         | ''      | '20130912'
 'BAT54-7-F' | 'SMLF'    | 'IC'     | 'BC0BAT54Z53SEL1'(!) = ''       | ''               | 'BC0BAT54Z53SEL1' |'SOT23_123XB'| 'DIODE BAT54-7-F(30V,200MA SCHOTTKY)SELA' | 'DDS'   | 'BAT54-7-F' | ''           | 'EU'      | 'IC'  | ''      | 'SEL_15QPN.xlsx' | 'S50-STEVE' | 'DDS_BAT54-7-F(A.C.S-7-F).pdf' | ''            | ''     | ''  | ''         | ''      | '20230705'
 'BAT54-7-F' | 'SMLF'    | 'EMPTY'  | 'BC0BAT54Z53SEL1'(!) = ''       | ''               | 'BC0BAT54Z53SEL1' |'SOT23_123XB'| 'DIODE BAT54-7-F(30V,200MA SCHOTTKY)SELA' | 'DDS'   | 'BAT54-7-F' | ''           | 'EU'      | 'IC'  | ''      | 'SEL_15QPN.xlsx' | 'S50-STEVE' | 'DDS_BAT54-7-F(A.C.S-7-F).pdf' | ''            | ''     | ''  | ''         | ''      | '20230705'

END_PART

END.

